#ISCELL
  mstr_misc dns *
  *
#ISCELL
  pure_quanta quanta_title_block_c *
  *
#ISCELL
  standard offpage *
  page84_i1
#ISCELL
  standard offpage *
  page84_i100
#CELL
  pure_quanta q_cap *
  page84_i101
#ISCELL
  pure_quanta_power universal_gnd *
  page84_i102
#CELL
  pure_quanta q_res *
  page84_i103
#CELL
  pure_quanta q_res *
  page84_i104
#ISCELL
  pure_quanta_power universal_gnd *
  page84_i105
#CELL
  pure_quanta q_res *
  page84_i106
#ISCELL
  standard offpage *
  page84_i107
#ISCELL
  pure_quanta_power universal_gnd *
  page84_i110
#CELL
  pure_quanta mosfet_nch_dual *
  page84_i111
#CELL
  pure_quanta q_res *
  page84_i112
#ISCELL
  pure_quanta_power universal_gnd *
  page84_i113
#CELL
  pure_quanta q_res *
  page84_i114
#ISCELL
  pure_quanta_power universal_gnd *
  page84_i115
#CELL
  pure_quanta q_cap *
  page84_i116
#ISCELL
  standard offpage *
  page84_i117
#CELL
  pure_quanta q_res *
  page84_i118
#ISCELL
  pure_quanta_power universal_power *
  page84_i119
#ISCELL
  pure_quanta_power universal_power *
  page84_i120
#CELL
  pure_quanta mosfet_nch_dual *
  page84_i121
#ISCELL
  standard offpage *
  page84_i25
#ISCELL
  standard offpage *
  page84_i26
#CELL
  pure_quanta q_res *
  page84_i27
#ISCELL
  mstr_standard offpage *
  page84_i28
#ISCELL
  standard offpage *
  page84_i29
#ISCELL
  pure_quanta_power universal_power *
  page84_i30
#ISCELL
  standard offpage *
  page84_i31
#ISCELL
  standard offpage *
  page84_i32
#ISCELL
  standard offpage *
  page84_i33
#ISCELL
  standard offpage *
  page84_i34
#CELL
  pure_quanta q_res *
  page84_i35
#CELL
  pure_quanta q_res *
  page84_i36
#CELL
  pure_quanta q_res *
  page84_i37
#CELL
  pure_quanta q_res *
  page84_i38
#ISCELL
  pure_quanta_power universal_gnd *
  page84_i39
#ISCELL
  pure_quanta_power universal_gnd *
  page84_i40
#CELL
  pure_quanta conn8_hbb1081l200d8h *
  page84_i41
#CELL
  pure_quanta q_cap *
  page84_i42
#ISCELL
  pure_quanta_power universal_power *
  page84_i43
#ISCELL
  standard offpage *
  page84_i44
#CELL
  pure_quanta q_res *
  page84_i45
#CELL
  pure_quanta q_res *
  page84_i46
#ISCELL
  pure_quanta_power universal_gnd *
  page84_i47
#CELL
  pure_quanta mosfet_dual_6p *
  page84_i48
#CELL
  pure_quanta q_res *
  page84_i5
#ISCELL
  pure_quanta_power universal_gnd *
  page84_i51
#ISCELL
  standard offpage *
  page84_i52
#CELL
  pure_quanta q_res *
  page84_i53
#ISCELL
  standard offpage *
  page84_i54
#ISCELL
  standard offpage *
  page84_i55
#ISCELL
  standard offpage *
  page84_i56
#CELL
  pure_quanta q_res *
  page84_i57
#ISCELL
  standard offpage *
  page84_i58
#ISCELL
  standard offpage *
  page84_i59
#CELL
  pure_quanta q_res *
  page84_i6
#ISCELL
  standard offpage *
  page84_i60
#CELL
  pure_quanta q_res *
  page84_i61
#ISCELL
  standard offpage *
  page84_i62
#CELL
  pure_quanta q_res *
  page84_i63
#ISCELL
  pure_quanta_power universal_power *
  page84_i64
#CELL
  pure_quanta mosfet_nch_dual *
  page84_i65
#ISCELL
  pure_quanta_power universal_gnd *
  page84_i66
#CELL
  pure_quanta q_res *
  page84_i67
#ISCELL
  pure_quanta_power universal_power *
  page84_i68
#ISCELL
  pure_quanta_power universal_gnd *
  page84_i69
#ISCELL
  pure_quanta_power vcc_core *
  page84_i7
#CELL
  pure_quanta q_res *
  page84_i70
#ISCELL
  pure_quanta_power universal_power *
  page84_i71
#CELL
  pure_quanta mosfet_nch_dual *
  page84_i73
#ISCELL
  standard offpage *
  page84_i74
#CELL
  pure_quanta q_res *
  page84_i75
#ISCELL
  standard offpage *
  page84_i76
#CELL
  pure_quanta q_res *
  page84_i77
#ISCELL
  pure_quanta_power universal_gnd *
  page84_i78
#ISCELL
  standard offpage *
  page84_i8
#ISCELL
  standard offpage *
  page84_i81
#CELL
  pure_quanta q_res *
  page84_i82
#ISCELL
  standard offpage *
  page84_i83
#CELL
  pure_quanta q_res *
  page84_i84
#ISCELL
  standard offpage *
  page84_i85
#CELL
  pure_quanta q_cap *
  page84_i88
#ISCELL
  pure_quanta_power universal_gnd *
  page84_i89
#ISCELL
  standard offpage *
  page84_i90
#CELL
  pure_quanta q_res *
  page84_i91
#ISCELL
  standard offpage *
  page84_i92
#ISCELL
  standard offpage *
  page84_i93
#CELL
  pure_quanta q_res *
  page84_i94
#ISCELL
  standard offpage *
  page84_i95
#CELL
  pure_quanta q_led *
  page84_i96
#CELL
  pure_quanta q_led *
  page84_i97
